(kicad_pcb
	(version 20241229)
	(generator "pcbnew")
	(generator_version "9.0")
	(general
		(thickness 1.6642)
		(legacy_teardrops no)
	)
	(paper "A3")
	(title_block
		(title "PolarFire SoM")
		(date "2025-07-22")
		(rev "1.1.4")
		(company "Antmicro Ltd")
		(comment 1 "www.antmicro.com")
		(comment 9 "footprints 431-434 of 470")
	)
	(layers
		(0 "F.Cu" mixed)
		(4 "In1.Cu" power)
		(6 "In2.Cu" signal)
		(8 "In3.Cu" power)
		(10 "In4.Cu" signal)
		(12 "In5.Cu" power)
		(14 "In6.Cu" power)
		(16 "In7.Cu" signal)
		(18 "In8.Cu" power)
		(20 "In9.Cu" signal)
		(22 "In10.Cu" power)
		(24 "In11.Cu" signal)
		(26 "In12.Cu" signal)
		(2 "B.Cu" mixed)
		(9 "F.Adhes" user "F.Adhesive")
		(11 "B.Adhes" user "B.Adhesive")
		(13 "F.Paste" user)
		(15 "B.Paste" user)
		(5 "F.SilkS" user "F.Silkscreen")
		(7 "B.SilkS" user "B.Silkscreen")
		(1 "F.Mask" user)
		(3 "B.Mask" user)
		(17 "Dwgs.User" user "User.Drawings")
		(19 "Cmts.User" user "User.Comments")
		(21 "Eco1.User" user "User.Eco1")
		(23 "Eco2.User" user "User.Eco2")
		(25 "Edge.Cuts" user)
		(27 "Margin" user)
		(31 "F.CrtYd" user "F.Courtyard")
		(29 "B.CrtYd" user "B.Courtyard")
		(35 "F.Fab" user)
		(33 "B.Fab" user)
	)
	(footprint "antmicro-footprints:C_0402_1005Metric"
		(layer "B.Cu")
		(at 208.25 136.35 180)
		(descr "Capacitor SMD 0402")
		(tags "capacitor SMD 0402")
		(property "Reference" "C125"
			(at 0.8 -0.4 0)
			(layer "B.SilkS")
			(effects
				(font
					(size 0.7 0.7)
					(thickness 0.15)
				)
				(justify left bottom mirror)
			)
		)
		(property "Value" "C_100n_0402"
			(at -1.022927 -2.155213 0)
			(layer "B.Fab")
			(hide yes)
			(effects
				(font
					(size 0.7 0.7)
					(thickness 0.15)
				)
				(justify left bottom mirror)
			)
		)
		(property "Datasheet" "https://www.murata.com/products/productdetail?partno=GRM155R61H104KE14%23"
			(at 0 0 180)
			(layer "F.Fab")
			(hide yes)
			(effects
				(font
					(size 1.27 1.27)
					(thickness 0.15)
				)
			)
		)
		(property "Description" "SMD Multilayer Ceramic Capacitor, 0.1 µF, 50 V, 0402 [1005 Metric], ± 10%, X5R, GRM Series"
			(at 0 0 180)
			(layer "F.Fab")
			(hide yes)
			(effects
				(font
					(size 1.27 1.27)
					(thickness 0.15)
				)
			)
		)
		(property "Author" "Antmicro"
			(at 416.5 272.7 0)
			(layer "B.Fab")
			(hide yes)
			(effects
				(font
					(size 1 1)
					(thickness 0.15)
				)
				(justify mirror)
			)
		)
		(property "Dielectric" "X5R"
			(at 416.5 272.7 0)
			(layer "B.Fab")
			(hide yes)
			(effects
				(font
					(size 1 1)
					(thickness 0.15)
				)
				(justify mirror)
			)
		)
		(property "License" "Apache-2.0"
			(at 416.5 272.7 0)
			(layer "B.Fab")
			(hide yes)
			(effects
				(font
					(size 1 1)
					(thickness 0.15)
				)
				(justify mirror)
			)
		)
		(property "MPN" "GRM155R61H104KE14D"
			(at 416.5 272.7 0)
			(layer "B.Fab")
			(hide yes)
			(effects
				(font
					(size 1 1)
					(thickness 0.15)
				)
				(justify mirror)
			)
		)
		(property "Manufacturer" "Murata"
			(at 416.5 272.7 0)
			(layer "B.Fab")
			(hide yes)
			(effects
				(font
					(size 1 1)
					(thickness 0.15)
				)
				(justify mirror)
			)
		)
		(property "Public" ""
			(at 416.5 272.7 0)
			(layer "B.Fab")
			(hide yes)
			(effects
				(font
					(size 1 1)
					(thickness 0.15)
				)
				(justify mirror)
			)
		)
		(property "Val" "100n"
			(at 416.5 272.7 0)
			(layer "B.Fab")
			(hide yes)
			(effects
				(font
					(size 1 1)
					(thickness 0.15)
				)
				(justify mirror)
			)
		)
		(property "Voltage" "50V"
			(at 416.5 272.7 0)
			(layer "B.Fab")
			(hide yes)
			(effects
				(font
					(size 1 1)
					(thickness 0.15)
				)
				(justify mirror)
			)
		)
		(sheetname "/FPGA GPIO/")
		(sheetfile "fpga-gpio.kicad_sch")
		(attr smd)
		(fp_rect
			(start -0.925 0.47)
			(end 0.925 -0.47)
			(stroke
				(width 0.05)
				(type default)
			)
			(fill no)
			(layer "B.CrtYd")
		)
		(fp_line
			(start 0.504 0.25)
			(end 0.504 -0.248)
			(stroke
				(width 0.15)
				(type solid)
			)
			(layer "B.Fab")
		)
		(fp_line
			(start 0.504 -0.248)
			(end -0.494 -0.248)
			(stroke
				(width 0.15)
				(type solid)
			)
			(layer "B.Fab")
		)
		(fp_line
			(start -0.494 0.25)
			(end 0.504 0.25)
			(stroke
				(width 0.15)
				(type solid)
			)
			(layer "B.Fab")
		)
		(fp_line
			(start -0.494 -0.248)
			(end -0.494 0.25)
			(stroke
				(width 0.15)
				(type solid)
			)
			(layer "B.Fab")
		)
		(fp_text user "Author: Antmicro"
			(at -0.939 -3.399 0)
			(layer "B.Fab")
			(effects
				(font
					(size 0.7 0.7)
					(thickness 0.15)
				)
				(justify left bottom mirror)
			)
		)
		(fp_text user "${REFERENCE}"
			(at -0.939 -4.599 0)
			(layer "B.Fab")
			(effects
				(font
					(size 0.7 0.7)
					(thickness 0.15)
				)
				(justify left bottom mirror)
			)
		)
		(fp_text user "License: Apache-2.0"
			(at -0.939 -5.799 0)
			(layer "B.Fab")
			(effects
				(font
					(size 0.7 0.7)
					(thickness 0.15)
				)
				(justify left bottom mirror)
			)
		)
		(pad "1" smd roundrect
			(at -0.48 0 180)
			(size 0.59 0.64)
			(layers "B.Cu" "B.Mask" "B.Paste")
			(roundrect_rratio 0.25)
			(net 50 "+3V3")
			(pintype "passive")
		)
		(pad "2" smd roundrect
			(at 0.48 0 180)
			(size 0.59 0.64)
			(layers "B.Cu" "B.Mask" "B.Paste")
			(roundrect_rratio 0.25)
			(net 417 "GND")
			(pintype "passive")
		)
	)
	(footprint "antmicro-footprints:TP_SMD_0.75mm"
		(layer "B.Cu")
		(at 176.45 142.95 180)
		(property "Reference" "TP7"
			(at -2.25 1.275 45)
			(layer "B.SilkS")
			(hide yes)
			(effects
				(font
					(size 0.7 0.7)
					(thickness 0.15)
				)
				(justify left bottom mirror)
			)
		)
		(property "Value" "TP_0.75mm_SMD"
			(at 0 -1.2 0)
			(layer "B.Fab")
			(hide yes)
			(effects
				(font
					(size 0.7 0.7)
					(thickness 0.15)
				)
				(justify left bottom mirror)
			)
		)
		(property "Description" "SMT test point"
			(at 0 0 0)
			(layer "B.Fab")
			(hide yes)
			(effects
				(font
					(size 1.27 1.27)
					(thickness 0.15)
				)
				(justify mirror)
			)
		)
		(property "MPN" ""
			(at 0 0 0)
			(unlocked yes)
			(layer "B.Fab")
			(hide yes)
			(effects
				(font
					(size 1 1)
					(thickness 0.15)
				)
				(justify mirror)
			)
		)
		(property "Manufacturer" ""
			(at 0 0 0)
			(unlocked yes)
			(layer "B.Fab")
			(hide yes)
			(effects
				(font
					(size 1 1)
					(thickness 0.15)
				)
				(justify mirror)
			)
		)
		(property "Author" "Antmicro"
			(at 0 0 0)
			(unlocked yes)
			(layer "B.Fab")
			(hide yes)
			(effects
				(font
					(size 1 1)
					(thickness 0.15)
				)
				(justify mirror)
			)
		)
		(property "License" "Apache-2.0"
			(at 0 0 0)
			(unlocked yes)
			(layer "B.Fab")
			(hide yes)
			(effects
				(font
					(size 1 1)
					(thickness 0.15)
				)
				(justify mirror)
			)
		)
		(property "Public" "False"
			(at 0 0 0)
			(unlocked yes)
			(layer "B.Fab")
			(hide yes)
			(effects
				(font
					(size 1 1)
					(thickness 0.15)
				)
				(justify mirror)
			)
		)
		(sheetname "/Supply/")
		(sheetfile "supply.kicad_sch")
		(attr exclude_from_pos_files exclude_from_bom)
		(fp_circle
			(center 0 0)
			(end 0.475 0)
			(stroke
				(width 0.05)
				(type default)
			)
			(fill no)
			(layer "B.CrtYd")
		)
		(fp_text user "License: Apache-2.0"
			(at -0.4 -5.101 0)
			(layer "B.Fab")
			(effects
				(font
					(size 0.7 0.7)
					(thickness 0.15)
				)
				(justify left bottom mirror)
			)
		)
		(fp_text user "Author: Antmicro"
			(at -0.4 -3.901 0)
			(layer "B.Fab")
			(effects
				(font
					(size 0.7 0.7)
					(thickness 0.15)
				)
				(justify left bottom mirror)
			)
		)
		(fp_text user "${REFERENCE}"
			(at -0.4 -2.7 0)
			(layer "B.Fab")
			(effects
				(font
					(size 0.7 0.7)
					(thickness 0.15)
				)
				(justify left bottom mirror)
			)
		)
		(pad "1" smd circle
			(at 0 0 180)
			(size 0.75 0.75)
			(layers "B.Cu" "B.Mask")
			(net 406 "/Supply/SENSE2_P")
			(pinfunction "1")
			(pintype "passive")
		)
	)
	(footprint "antmicro-footprints:SOT-886"
		(layer "B.Cu")
		(at 187.8 140.893 -90)
		(property "Reference" "U18"
			(at -3.218 -0.925 90)
			(layer "B.SilkS")
			(effects
				(font
					(size 0.7 0.7)
					(thickness 0.15)
				)
				(justify left bottom mirror)
			)
		)
		(property "Value" "74LVC1T45GM"
			(at -2.492 -1.647 90)
			(layer "B.Fab")
			(hide yes)
			(effects
				(font
					(size 0.7 0.7)
					(thickness 0.15)
				)
				(justify left bottom mirror)
			)
		)
		(property "Datasheet" "http://www.ti.com/general/docs/suppproductinfo.tsp?distId=10&gotoUrl=http%3A%2F%2Fwww.ti.com%2Flit%2Fgpn%2Fsn74lvc1t45"
			(at 0 0 270)
			(layer "F.Fab")
			(hide yes)
			(effects
				(font
					(size 1.27 1.27)
					(thickness 0.15)
				)
			)
		)
		(property "Description" "Transceiver, Translating, 74LVC1T45, 74LVC Family, 1.2V to 5.5V Supply, XSON-6"
			(at 0 0 270)
			(layer "F.Fab")
			(hide yes)
			(effects
				(font
					(size 1.27 1.27)
					(thickness 0.15)
				)
			)
		)
		(property "Author" "Antmicro"
			(at 46.907 328.693 0)
			(layer "B.Fab")
			(hide yes)
			(effects
				(font
					(size 1 1)
					(thickness 0.15)
				)
				(justify mirror)
			)
		)
		(property "License" "Apache-2.0"
			(at 46.907 328.693 0)
			(layer "B.Fab")
			(hide yes)
			(effects
				(font
					(size 1 1)
					(thickness 0.15)
				)
				(justify mirror)
			)
		)
		(property "MPN" "74LVC1T45GM-Q100X"
			(at 46.907 328.693 0)
			(layer "B.Fab")
			(hide yes)
			(effects
				(font
					(size 1 1)
					(thickness 0.15)
				)
				(justify mirror)
			)
		)
		(property "Manufacturer" "Nexperia"
			(at 46.907 328.693 0)
			(layer "B.Fab")
			(hide yes)
			(effects
				(font
					(size 1 1)
					(thickness 0.15)
				)
				(justify mirror)
			)
		)
		(sheetname "/FPGA GPIO/")
		(sheetfile "fpga-gpio.kicad_sch")
		(attr smd)
		(fp_line
			(start -0.843 0.491)
			(end -0.843 -0.183)
			(stroke
				(width 0.15)
				(type solid)
			)
			(layer "B.SilkS")
		)
		(fp_line
			(start 0.858 0.491)
			(end 0.858 -0.509)
			(stroke
				(width 0.15)
				(type solid)
			)
			(layer "B.SilkS")
		)
		(fp_circle
			(center -0.493 -0.847)
			(end -0.443 -0.847)
			(stroke
				(width 0.15)
				(type solid)
			)
			(fill yes)
			(layer "B.SilkS")
		)
		(fp_rect
			(start -1.23 1)
			(end 1.22 -0.99)
			(stroke
				(width 0.05)
				(type solid)
			)
			(fill no)
			(layer "B.CrtYd")
		)
		(fp_line
			(start -0.843 0.616)
			(end 0.858 0.616)
			(stroke
				(width 0.15)
				(type solid)
			)
			(layer "B.Fab")
		)
		(fp_line
			(start -0.843 0.616)
			(end -0.843 -0.634)
			(stroke
				(width 0.15)
				(type solid)
			)
			(layer "B.Fab")
		)
		(fp_line
			(start 0.858 0.616)
			(end 0.858 -0.634)
			(stroke
				(width 0.15)
				(type solid)
			)
			(layer "B.Fab")
		)
		(fp_line
			(start -0.843 -0.434)
			(end -0.644 -0.634)
			(stroke
				(width 0.15)
				(type solid)
			)
			(layer "B.Fab")
		)
		(fp_line
			(start 0.858 -0.634)
			(end -0.843 -0.634)
			(stroke
				(width 0.15)
				(type solid)
			)
			(layer "B.Fab")
		)
		(fp_text user "Author: Antmicro"
			(at -2.492 -4.847 90)
			(layer "B.Fab")
			(effects
				(font
					(size 0.7 0.7)
					(thickness 0.15)
				)
				(justify left bottom mirror)
			)
		)
		(fp_text user "${REFERENCE}"
			(at -2.492 -3.647 90)
			(layer "B.Fab")
			(effects
				(font
					(size 0.7 0.7)
					(thickness 0.15)
				)
				(justify left bottom mirror)
			)
		)
		(fp_text user "License: Apache-2.0"
			(at -2.492 -6.047 90)
			(layer "B.Fab")
			(effects
				(font
					(size 0.7 0.7)
					(thickness 0.15)
				)
				(justify left bottom mirror)
			)
		)
		(pad "1" smd rect
			(at -0.493 -0.347 270)
			(size 0.27 0.325)
			(layers "B.Cu" "B.Mask" "B.Paste")
			(net 649 "VDD")
			(pinfunction "VCCA")
			(pintype "power_in")
			(solder_mask_margin 0.05)
		)
		(pad "2" smd rect
			(at 0.005 -0.347 270)
			(size 0.27 0.325)
			(layers "B.Cu" "B.Mask" "B.Paste")
			(net 417 "GND")
			(pinfunction "GND")
			(pintype "power_in")
			(solder_mask_margin 0.05)
		)
		(pad "3" smd rect
			(at 0.505 -0.347 270)
			(size 0.27 0.325)
			(layers "B.Cu" "B.Mask" "B.Paste")
			(net 356 "/FPGA GPIO/HDMI0_HPD_SRC")
			(pinfunction "A")
			(pintype "bidirectional")
			(solder_mask_margin 0.05)
		)
		(pad "4" smd rect
			(at 0.505 0.33 90)
			(size 0.27 0.325)
			(layers "B.Cu" "B.Mask" "B.Paste")
			(net 505 "PI3HDX511F_HOTPLUG")
			(pinfunction "B")
			(pintype "bidirectional")
			(solder_mask_margin 0.05)
		)
		(pad "5" smd rect
			(at 0.005 0.33 90)
			(size 0.27 0.325)
			(layers "B.Cu" "B.Mask" "B.Paste")
			(net 417 "GND")
			(pinfunction "DIR")
			(pintype "input")
			(solder_mask_margin 0.05)
		)
		(pad "6" smd rect
			(at -0.493 0.33 90)
			(size 0.27 0.325)
			(layers "B.Cu" "B.Mask" "B.Paste")
			(net 50 "+3V3")
			(pinfunction "VCCB")
			(pintype "power_in")
			(solder_mask_margin 0.05)
		)
	)
	(footprint "antmicro-footprints:R_0402_1005Metric"
		(layer "B.Cu")
		(at 184.35 122.45)
		(descr "Resistor SMD 0402")
		(tags "resistor SMD 0402")
		(property "Reference" "R76"
			(at 2.975 0.25 180)
			(layer "B.SilkS")
			(effects
				(font
					(size 0.7 0.7)
					(thickness 0.15)
				)
				(justify left bottom mirror)
			)
		)
		(property "Value" "R_240R_0402"
			(at -1.011843 -1.772047 180)
			(layer "B.Fab")
			(hide yes)
			(effects
				(font
					(size 0.7 0.7)
					(thickness 0.15)
				)
				(justify left bottom mirror)
			)
		)
		(property "Datasheet" "https://www.bourns.com/docs/product-datasheets/cr.pdf"
			(at 0 0 0)
			(layer "F.Fab")
			(hide yes)
			(effects
				(font
					(size 1.27 1.27)
					(thickness 0.15)
				)
			)
		)
		(property "Description" "SMD Chip Resistor, 240 ohm, ± 1%, 63 mW, 0402 [1005 Metric], Thick Film, General Purpose"
			(at 0 0 0)
			(layer "F.Fab")
			(hide yes)
			(effects
				(font
					(size 1.27 1.27)
					(thickness 0.15)
				)
			)
		)
		(property "Author" "Antmicro"
			(at 0 0 0)
			(layer "B.Fab")
			(hide yes)
			(effects
				(font
					(size 1 1)
					(thickness 0.15)
				)
				(justify mirror)
			)
		)
		(property "License" "Apache-2.0"
			(at 0 0 0)
			(layer "B.Fab")
			(hide yes)
			(effects
				(font
					(size 1 1)
					(thickness 0.15)
				)
				(justify mirror)
			)
		)
		(property "MPN" "CR0402-FX-2400GLF"
			(at 0 0 0)
			(layer "B.Fab")
			(hide yes)
			(effects
				(font
					(size 1 1)
					(thickness 0.15)
				)
				(justify mirror)
			)
		)
		(property "Manufacturer" "Bourns"
			(at 0 0 0)
			(layer "B.Fab")
			(hide yes)
			(effects
				(font
					(size 1 1)
					(thickness 0.15)
				)
				(justify mirror)
			)
		)
		(property "Public" ""
			(at 0 0 0)
			(layer "B.Fab")
			(hide yes)
			(effects
				(font
					(size 1 1)
					(thickness 0.15)
				)
				(justify mirror)
			)
		)
		(property "Tolerance" "1%"
			(at 0 0 0)
			(layer "B.Fab")
			(hide yes)
			(effects
				(font
					(size 1 1)
					(thickness 0.15)
				)
				(justify mirror)
			)
		)
		(property "Val" "240R"
			(at 0 0 0)
			(layer "B.Fab")
			(hide yes)
			(effects
				(font
					(size 1 1)
					(thickness 0.15)
				)
				(justify mirror)
			)
		)
		(sheetname "/LPDDR4/")
		(sheetfile "lpddr.kicad_sch")
		(attr smd)
		(fp_rect
			(start -0.925 0.47)
			(end 0.925 -0.47)
			(stroke
				(width 0.05)
				(type default)
			)
			(fill no)
			(layer "B.CrtYd")
		)
		(fp_rect
			(start -0.5 0.25)
			(end 0.5 -0.25)
			(stroke
				(width 0.15)
				(type solid)
			)
			(fill no)
			(layer "B.Fab")
		)
		(fp_text user "Author: Antmicro"
			(at -0.95 -4.169 180)
			(layer "B.Fab")
			(effects
				(font
					(size 0.7 0.7)
					(thickness 0.15)
				)
				(justify left bottom mirror)
			)
		)
		(fp_text user "License: Apache-2.0"
			(at -0.95 -5.169 180)
			(layer "B.Fab")
			(effects
				(font
					(size 0.7 0.7)
					(thickness 0.15)
				)
				(justify left bottom mirror)
			)
		)
		(fp_text user "${REFERENCE}"
			(at -0.95 -3.168 180)
			(layer "B.Fab")
			(effects
				(font
					(size 0.7 0.7)
					(thickness 0.15)
				)
				(justify left bottom mirror)
			)
		)
		(pad "1" smd roundrect
			(at -0.48 0)
			(size 0.59 0.64)
			(layers "B.Cu" "B.Mask" "B.Paste")
			(roundrect_rratio 0.25)
			(net 271 "Net-(U12A-ZQ0)")
			(pintype "passive")
		)
		(pad "2" smd roundrect
			(at 0.48 0)
			(size 0.59 0.64)
			(layers "B.Cu" "B.Mask" "B.Paste")
			(roundrect_rratio 0.25)
			(net 2 "+1V1")
			(pintype "passive")
		)
	)
)
